(kicad_pcb
	(version 20260206)
	(generator "pcbnew")
	(generator_version "10.0")
	(general
		(thickness 1.6)
		(legacy_teardrops no)
	)
	(paper "A4")
	(title_block
		(title "15969-1a.1015WZS0858.brd")
		(comment 1 "Tioga Pass / footprints 59-66 of 295")
	)
	(layers
		(0 "F.Cu" signal "TOP")
		(4 "In1.Cu" signal "L2GND")
		(6 "In2.Cu" signal "L3")
		(8 "In3.Cu" signal "L4")
		(10 "In4.Cu" signal "L5GND")
		(2 "B.Cu" signal "BOTTOM")
		(9 "F.Adhes" user "F.Adhesive")
		(11 "B.Adhes" user "B.Adhesive")
		(13 "F.Paste" user "Package Geometry/Pastemask Top")
		(15 "B.Paste" user "Package Geometry/Pastemask Bottom")
		(5 "F.SilkS" user "Ref Des/Silkscreen Top")
		(7 "B.SilkS" user "Ref Des/Silkscreen Bottom")
		(1 "F.Mask" user "Board Geometry/Soldermask Top")
		(3 "B.Mask" user "Board Geometry/Soldermask Bottom")
		(17 "Dwgs.User" user "User.Drawings")
		(19 "Cmts.User" user "User.Comments")
		(21 "Eco1.User" user "User.Eco1")
		(23 "Eco2.User" user "User.Eco2")
		(25 "Edge.Cuts" user "Board Geometry/Outline")
		(27 "Margin" user)
		(31 "F.CrtYd" user "Package Geometry/Place Bound Top")
		(29 "B.CrtYd" user "Package Geometry/Place Bound Bottom")
		(35 "F.Fab" user "Ref Des/Assembly Top")
		(33 "B.Fab" user "Ref Des/Assembly Bottom")
	)
	(footprint ""
		(layer "F.Cu")
		(at 18.7198 -28.3718 90)
		(property "Reference" "C55"
			(at 0 0 90)
			(layer "F.SilkS")
			(hide yes)
			(effects
				(font
					(size 1.27 1.27)
				)
			)
		)
		(property "Value" "SCD1U25V2KX-2-GP"
			(at 1.1811 -2.7051 90)
			(unlocked yes)
			(layer "F.Fab")
			(hide yes)
			(effects
				(font
					(size 1.016 1.016)
					(thickness 0.1524)
				)
			)
		)
		(property "Device Type" "C402H22"
			(at 1.1811 -4.2291 90)
			(unlocked yes)
			(layer "F.Fab")
			(hide yes)
			(effects
				(font
					(size 1.016 1.016)
					(thickness 0.1524)
				)
			)
		)
		(duplicate_pad_numbers_are_jumpers no)
		(fp_rect
			(start -0.4318 0.9525)
			(end 0.4318 -0.9525)
			(stroke
				(width 0)
				(type default)
			)
			(fill no)
			(layer "F.CrtYd")
		)
		(fp_rect
			(start -0.4318 0.9525)
			(end 0.4318 -0.9525)
			(stroke
				(width 0)
				(type default)
			)
			(fill no)
			(layer "F.Fab")
		)
		(pad "1" smd custom
			(at 0 -0.4445 90)
			(size 0.1524 0.1524)
			(layers "F.Cu" "F.Mask" "F.Paste")
			(net "P12V")
			(options
				(clearance outline)
				(anchor circle)
			)
			(primitives
				(gr_poly
					(pts
						(arc
							(start 0.3048 -0.2032)
							(mid 0.275042 -0.275042)
							(end 0.2032 -0.3048)
						)
						(arc
							(start -0.2032 -0.3048)
							(mid -0.275042 -0.275042)
							(end -0.3048 -0.2032)
						)
						(arc
							(start -0.3048 0.2032)
							(mid -0.275042 0.275042)
							(end -0.2032 0.3048)
						)
						(arc
							(start 0.2032 0.3048)
							(mid 0.275042 0.275042)
							(end 0.3048 0.2032)
						)
					)
					(width 0)
					(fill yes)
				)
			)
		)
		(pad "2" smd custom
			(at 0 0.4445 90)
			(size 0.1524 0.1524)
			(layers "F.Cu" "F.Mask" "F.Paste")
			(net "GND")
			(options
				(clearance outline)
				(anchor circle)
			)
			(primitives
				(gr_poly
					(pts
						(arc
							(start 0.3048 -0.2032)
							(mid 0.275042 -0.275042)
							(end 0.2032 -0.3048)
						)
						(arc
							(start -0.2032 -0.3048)
							(mid -0.275042 -0.275042)
							(end -0.3048 -0.2032)
						)
						(arc
							(start -0.3048 0.2032)
							(mid -0.275042 0.275042)
							(end -0.2032 0.3048)
						)
						(arc
							(start 0.2032 0.3048)
							(mid 0.275042 0.275042)
							(end 0.3048 0.2032)
						)
					)
					(width 0)
					(fill yes)
				)
			)
		)
	)
	(footprint ""
		(layer "F.Cu")
		(at 21.5519 5.8547 90)
		(property "Reference" "R2"
			(at 0 0 90)
			(layer "F.SilkS")
			(hide yes)
			(effects
				(font
					(size 1.27 1.27)
				)
			)
		)
		(property "Value" "475R2F-L1-GP"
			(at 0.064008 -3.993896 90)
			(unlocked yes)
			(layer "F.Fab")
			(hide yes)
			(effects
				(font
					(size 1.016 1.016)
					(thickness 0.1524)
				)
			)
		)
		(property "Device Type" "R402H16"
			(at 0.064008 -5.517896 90)
			(unlocked yes)
			(layer "F.Fab")
			(hide yes)
			(effects
				(font
					(size 1.016 1.016)
					(thickness 0.1524)
				)
			)
		)
		(duplicate_pad_numbers_are_jumpers no)
		(fp_line
			(start 0.508 -0.9398)
			(end -0.508 -0.9398)
			(stroke
				(width 0.1524)
				(type default)
			)
			(layer "F.SilkS")
		)
		(fp_line
			(start -0.508 -0.9398)
			(end -0.508 0.9398)
			(stroke
				(width 0.1524)
				(type default)
			)
			(layer "F.SilkS")
		)
		(fp_rect
			(start -0.508 0.9398)
			(end 0.508 -0.9398)
			(stroke
				(width 0)
				(type default)
			)
			(fill no)
			(layer "F.CrtYd")
		)
		(fp_rect
			(start -0.508 0.9398)
			(end 0.508 -0.9398)
			(stroke
				(width 0)
				(type default)
			)
			(fill no)
			(layer "F.Fab")
		)
		(pad "1" smd custom
			(at 0 -0.4445 90)
			(size 0.1397 0.1397)
			(layers "F.Cu" "F.Mask" "F.Paste")
			(net "GND")
			(options
				(clearance outline)
				(anchor circle)
			)
			(primitives
				(gr_poly
					(pts
						(arc
							(start -0.1778 -0.2794)
							(mid -0.249642 -0.249642)
							(end -0.2794 -0.1778)
						)
						(arc
							(start -0.2794 0.1778)
							(mid -0.249642 0.249642)
							(end -0.1778 0.2794)
						)
						(arc
							(start 0.1778 0.2794)
							(mid 0.249642 0.249642)
							(end 0.2794 0.1778)
						)
						(arc
							(start 0.2794 -0.1778)
							(mid 0.249642 -0.249642)
							(end 0.1778 -0.2794)
						)
					)
					(width 0)
					(fill yes)
				)
			)
		)
		(pad "2" smd custom
			(at 0 0.4445 90)
			(size 0.1397 0.1397)
			(layers "F.Cu" "F.Mask" "F.Paste")
			(net "FM_SLT_CFG1")
			(options
				(clearance outline)
				(anchor circle)
			)
			(primitives
				(gr_poly
					(pts
						(arc
							(start -0.1778 -0.2794)
							(mid -0.249642 -0.249642)
							(end -0.2794 -0.1778)
						)
						(arc
							(start -0.2794 0.1778)
							(mid -0.249642 0.249642)
							(end -0.1778 0.2794)
						)
						(arc
							(start 0.1778 0.2794)
							(mid 0.249642 0.249642)
							(end 0.2794 0.1778)
						)
						(arc
							(start 0.2794 -0.1778)
							(mid 0.249642 -0.249642)
							(end 0.1778 -0.2794)
						)
					)
					(width 0)
					(fill yes)
				)
			)
		)
	)
	(footprint ""
		(layer "F.Cu")
		(at 125.1458 1.5748 -90)
		(property "Reference" "R144"
			(at 0 0 270)
			(layer "F.SilkS")
			(hide yes)
			(effects
				(font
					(size 1.27 1.27)
				)
			)
		)
		(property "Value" "10KR2F-2-GP"
			(at 0.064008 -3.993896 270)
			(unlocked yes)
			(layer "F.Fab")
			(hide yes)
			(effects
				(font
					(size 1.016 1.016)
					(thickness 0.1524)
				)
			)
		)
		(property "Device Type" "R402H16"
			(at 0.064008 -5.517896 270)
			(unlocked yes)
			(layer "F.Fab")
			(hide yes)
			(effects
				(font
					(size 1.016 1.016)
					(thickness 0.1524)
				)
			)
		)
		(duplicate_pad_numbers_are_jumpers no)
		(fp_line
			(start -0.508 -0.9398)
			(end -0.508 0.9398)
			(stroke
				(width 0.1524)
				(type default)
			)
			(layer "F.SilkS")
		)
		(fp_line
			(start 0.508 -0.9398)
			(end -0.508 -0.9398)
			(stroke
				(width 0.1524)
				(type default)
			)
			(layer "F.SilkS")
		)
		(fp_rect
			(start -0.508 0.9398)
			(end 0.508 -0.9398)
			(stroke
				(width 0)
				(type default)
			)
			(fill no)
			(layer "F.CrtYd")
		)
		(fp_rect
			(start -0.508 0.9398)
			(end 0.508 -0.9398)
			(stroke
				(width 0)
				(type default)
			)
			(fill no)
			(layer "F.Fab")
		)
		(pad "1" smd custom
			(at 0 -0.4445 270)
			(size 0.1397 0.1397)
			(layers "F.Cu" "F.Mask" "F.Paste")
			(net "GPIO_P_IO1_6")
			(options
				(clearance outline)
				(anchor circle)
			)
			(primitives
				(gr_poly
					(pts
						(arc
							(start -0.1778 -0.2794)
							(mid -0.249642 -0.249642)
							(end -0.2794 -0.1778)
						)
						(arc
							(start -0.2794 0.1778)
							(mid -0.249642 0.249642)
							(end -0.1778 0.2794)
						)
						(arc
							(start 0.1778 0.2794)
							(mid 0.249642 0.249642)
							(end 0.2794 0.1778)
						)
						(arc
							(start 0.2794 -0.1778)
							(mid 0.249642 -0.249642)
							(end 0.1778 -0.2794)
						)
					)
					(width 0)
					(fill yes)
				)
			)
		)
		(pad "2" smd custom
			(at 0 0.4445 270)
			(size 0.1397 0.1397)
			(layers "F.Cu" "F.Mask" "F.Paste")
			(net "GND")
			(options
				(clearance outline)
				(anchor circle)
			)
			(primitives
				(gr_poly
					(pts
						(arc
							(start -0.1778 -0.2794)
							(mid -0.249642 -0.249642)
							(end -0.2794 -0.1778)
						)
						(arc
							(start -0.2794 0.1778)
							(mid -0.249642 0.249642)
							(end -0.1778 0.2794)
						)
						(arc
							(start 0.1778 0.2794)
							(mid 0.249642 0.249642)
							(end 0.2794 0.1778)
						)
						(arc
							(start 0.2794 -0.1778)
							(mid 0.249642 -0.249642)
							(end 0.1778 -0.2794)
						)
					)
					(width 0)
					(fill yes)
				)
			)
		)
	)
	(footprint ""
		(layer "F.Cu")
		(at 53.5432 -15.9004 -90)
		(property "Reference" "R30"
			(at 0 0 270)
			(layer "F.SilkS")
			(hide yes)
			(effects
				(font
					(size 1.27 1.27)
				)
			)
		)
		(property "Value" "0R2F-1-GP"
			(at 0.064008 -3.993896 270)
			(unlocked yes)
			(layer "F.Fab")
			(hide yes)
			(effects
				(font
					(size 1.016 1.016)
					(thickness 0.1524)
				)
			)
		)
		(property "Device Type" "R402H16"
			(at 0.064008 -5.517896 270)
			(unlocked yes)
			(layer "F.Fab")
			(hide yes)
			(effects
				(font
					(size 1.016 1.016)
					(thickness 0.1524)
				)
			)
		)
		(duplicate_pad_numbers_are_jumpers no)
		(fp_line
			(start -0.508 -0.9398)
			(end -0.508 0.9398)
			(stroke
				(width 0.1524)
				(type default)
			)
			(layer "F.SilkS")
		)
		(fp_line
			(start 0.508 -0.9398)
			(end -0.508 -0.9398)
			(stroke
				(width 0.1524)
				(type default)
			)
			(layer "F.SilkS")
		)
		(fp_rect
			(start -0.508 0.9398)
			(end 0.508 -0.9398)
			(stroke
				(width 0)
				(type default)
			)
			(fill no)
			(layer "F.CrtYd")
		)
		(fp_rect
			(start -0.508 0.9398)
			(end 0.508 -0.9398)
			(stroke
				(width 0)
				(type default)
			)
			(fill no)
			(layer "F.Fab")
		)
		(pad "1" smd custom
			(at 0 -0.4445 270)
			(size 0.1397 0.1397)
			(layers "F.Cu" "F.Mask" "F.Paste")
			(net "SMB_PCIE_SLOT2_ALERT_N")
			(options
				(clearance outline)
				(anchor circle)
			)
			(primitives
				(gr_poly
					(pts
						(arc
							(start -0.1778 -0.2794)
							(mid -0.249642 -0.249642)
							(end -0.2794 -0.1778)
						)
						(arc
							(start -0.2794 0.1778)
							(mid -0.249642 0.249642)
							(end -0.1778 0.2794)
						)
						(arc
							(start 0.1778 0.2794)
							(mid 0.249642 0.249642)
							(end 0.2794 0.1778)
						)
						(arc
							(start 0.2794 -0.1778)
							(mid 0.249642 -0.249642)
							(end 0.1778 -0.2794)
						)
					)
					(width 0)
					(fill yes)
				)
			)
		)
		(pad "2" smd custom
			(at 0 0.4445 270)
			(size 0.1397 0.1397)
			(layers "F.Cu" "F.Mask" "F.Paste")
			(net "SMB_ALERT_S2_B12_N")
			(options
				(clearance outline)
				(anchor circle)
			)
			(primitives
				(gr_poly
					(pts
						(arc
							(start -0.1778 -0.2794)
							(mid -0.249642 -0.249642)
							(end -0.2794 -0.1778)
						)
						(arc
							(start -0.2794 0.1778)
							(mid -0.249642 0.249642)
							(end -0.1778 0.2794)
						)
						(arc
							(start 0.1778 0.2794)
							(mid 0.249642 0.249642)
							(end 0.2794 0.1778)
						)
						(arc
							(start 0.2794 -0.1778)
							(mid 0.249642 -0.249642)
							(end 0.1778 -0.2794)
						)
					)
					(width 0)
					(fill yes)
				)
			)
		)
	)
	(footprint ""
		(layer "F.Cu")
		(at 127.635 -23.5458 -90)
		(property "Reference" "RU22"
			(at 0 0 270)
			(layer "F.SilkS")
			(hide yes)
			(effects
				(font
					(size 1.27 1.27)
				)
			)
		)
		(property "Value" "10KR2F-2-GP"
			(at 0.064008 -3.993896 270)
			(unlocked yes)
			(layer "F.Fab")
			(hide yes)
			(effects
				(font
					(size 1.016 1.016)
					(thickness 0.1524)
				)
			)
		)
		(property "Device Type" "R402H16"
			(at 0.064008 -5.517896 270)
			(unlocked yes)
			(layer "F.Fab")
			(hide yes)
			(effects
				(font
					(size 1.016 1.016)
					(thickness 0.1524)
				)
			)
		)
		(duplicate_pad_numbers_are_jumpers no)
		(fp_line
			(start -0.508 -0.9398)
			(end -0.508 0.9398)
			(stroke
				(width 0.1524)
				(type default)
			)
			(layer "F.SilkS")
		)
		(fp_line
			(start 0.508 -0.9398)
			(end -0.508 -0.9398)
			(stroke
				(width 0.1524)
				(type default)
			)
			(layer "F.SilkS")
		)
		(fp_rect
			(start -0.508 0.9398)
			(end 0.508 -0.9398)
			(stroke
				(width 0)
				(type default)
			)
			(fill no)
			(layer "F.CrtYd")
		)
		(fp_rect
			(start -0.508 0.9398)
			(end 0.508 -0.9398)
			(stroke
				(width 0)
				(type default)
			)
			(fill no)
			(layer "F.Fab")
		)
		(pad "1" smd custom
			(at 0 -0.4445 270)
			(size 0.1397 0.1397)
			(layers "F.Cu" "F.Mask" "F.Paste")
			(net "P3V3_USB_HUB")
			(options
				(clearance outline)
				(anchor circle)
			)
			(primitives
				(gr_poly
					(pts
						(arc
							(start -0.1778 -0.2794)
							(mid -0.249642 -0.249642)
							(end -0.2794 -0.1778)
						)
						(arc
							(start -0.2794 0.1778)
							(mid -0.249642 0.249642)
							(end -0.1778 0.2794)
						)
						(arc
							(start 0.1778 0.2794)
							(mid 0.249642 0.249642)
							(end 0.2794 0.1778)
						)
						(arc
							(start 0.2794 -0.1778)
							(mid 0.249642 -0.249642)
							(end 0.1778 -0.2794)
						)
					)
					(width 0)
					(fill yes)
				)
			)
		)
		(pad "2" smd custom
			(at 0 0.4445 270)
			(size 0.1397 0.1397)
			(layers "F.Cu" "F.Mask" "F.Paste")
			(net "VBUS_DET")
			(options
				(clearance outline)
				(anchor circle)
			)
			(primitives
				(gr_poly
					(pts
						(arc
							(start -0.1778 -0.2794)
							(mid -0.249642 -0.249642)
							(end -0.2794 -0.1778)
						)
						(arc
							(start -0.2794 0.1778)
							(mid -0.249642 0.249642)
							(end -0.1778 0.2794)
						)
						(arc
							(start 0.1778 0.2794)
							(mid 0.249642 0.249642)
							(end 0.2794 0.1778)
						)
						(arc
							(start 0.2794 -0.1778)
							(mid 0.249642 -0.249642)
							(end 0.1778 -0.2794)
						)
					)
					(width 0)
					(fill yes)
				)
			)
		)
	)
	(footprint ""
		(layer "F.Cu")
		(at 108.7882 3.1496)
		(property "Reference" "R17"
			(at 0 0 0)
			(layer "F.SilkS")
			(hide yes)
			(effects
				(font
					(size 1.27 1.27)
				)
			)
		)
		(property "Value" "10KR2F-2-GP"
			(at 0.064008 -3.993896 0)
			(unlocked yes)
			(layer "F.Fab")
			(hide yes)
			(effects
				(font
					(size 1.016 1.016)
					(thickness 0.1524)
				)
			)
		)
		(property "Device Type" "R402H16"
			(at 0.064008 -5.517896 0)
			(unlocked yes)
			(layer "F.Fab")
			(hide yes)
			(effects
				(font
					(size 1.016 1.016)
					(thickness 0.1524)
				)
			)
		)
		(duplicate_pad_numbers_are_jumpers no)
		(fp_line
			(start -0.508 -0.9398)
			(end -0.508 0.9398)
			(stroke
				(width 0.1524)
				(type default)
			)
			(layer "F.SilkS")
		)
		(fp_line
			(start 0.508 -0.9398)
			(end -0.508 -0.9398)
			(stroke
				(width 0.1524)
				(type default)
			)
			(layer "F.SilkS")
		)
		(fp_rect
			(start -0.508 0.9398)
			(end 0.508 -0.9398)
			(stroke
				(width 0)
				(type default)
			)
			(fill no)
			(layer "F.CrtYd")
		)
		(fp_rect
			(start -0.508 0.9398)
			(end 0.508 -0.9398)
			(stroke
				(width 0)
				(type default)
			)
			(fill no)
			(layer "F.Fab")
		)
		(pad "1" smd custom
			(at 0 -0.4445)
			(size 0.1397 0.1397)
			(layers "F.Cu" "F.Mask" "F.Paste")
			(net "SMB_B_HUB_A0")
			(options
				(clearance outline)
				(anchor circle)
			)
			(primitives
				(gr_poly
					(pts
						(arc
							(start -0.1778 -0.2794)
							(mid -0.249642 -0.249642)
							(end -0.2794 -0.1778)
						)
						(arc
							(start -0.2794 0.1778)
							(mid -0.249642 0.249642)
							(end -0.1778 0.2794)
						)
						(arc
							(start 0.1778 0.2794)
							(mid 0.249642 0.249642)
							(end 0.2794 0.1778)
						)
						(arc
							(start 0.2794 -0.1778)
							(mid 0.249642 -0.249642)
							(end 0.1778 -0.2794)
						)
					)
					(width 0)
					(fill yes)
				)
			)
		)
		(pad "2" smd custom
			(at 0 0.4445)
			(size 0.1397 0.1397)
			(layers "F.Cu" "F.Mask" "F.Paste")
			(net "GND")
			(options
				(clearance outline)
				(anchor circle)
			)
			(primitives
				(gr_poly
					(pts
						(arc
							(start -0.1778 -0.2794)
							(mid -0.249642 -0.249642)
							(end -0.2794 -0.1778)
						)
						(arc
							(start -0.2794 0.1778)
							(mid -0.249642 0.249642)
							(end -0.1778 0.2794)
						)
						(arc
							(start 0.1778 0.2794)
							(mid 0.249642 0.249642)
							(end 0.2794 0.1778)
						)
						(arc
							(start 0.2794 -0.1778)
							(mid 0.249642 -0.249642)
							(end 0.1778 -0.2794)
						)
					)
					(width 0)
					(fill yes)
				)
			)
		)
	)
	(footprint ""
		(layer "F.Cu")
		(at 25.1206 -31.9532 180)
		(property "Reference" "C91"
			(at 0 0 180)
			(layer "F.SilkS")
			(hide yes)
			(effects
				(font
					(size 1.27 1.27)
				)
			)
		)
		(property "Value" "SC22U16V5MX-4-GP"
			(at -0.0762 -6.1214 180)
			(unlocked yes)
			(layer "F.Fab")
			(hide yes)
			(effects
				(font
					(size 1.016 1.016)
					(thickness 0.1524)
				)
			)
		)
		(property "Device Type" "C805H58"
			(at -0.0762 -8.1534 180)
			(unlocked yes)
			(layer "F.Fab")
			(hide yes)
			(effects
				(font
					(size 1.016 1.016)
					(thickness 0.1524)
				)
			)
		)
		(duplicate_pad_numbers_are_jumpers no)
		(fp_line
			(start 0.635 0)
			(end -0.635 0)
			(stroke
				(width 0.508)
				(type default)
			)
			(layer "F.SilkS")
		)
		(fp_rect
			(start -0.9652 1.778)
			(end 0.9652 -1.778)
			(stroke
				(width 0)
				(type default)
			)
			(fill no)
			(layer "F.CrtYd")
		)
		(fp_poly
			(pts
				(xy -0.9652 -1.778) (xy 0.9652 -1.778) (xy 0.9652 1.778) (xy -0.9652 1.778)
			)
			(stroke
				(width 0)
				(type default)
			)
			(fill no)
			(layer "F.Fab")
		)
		(pad "1" smd rect
			(at 0 -0.9652 180)
			(size 1.397 1.143)
			(layers "F.Cu" "F.Mask" "F.Paste")
			(net "P12V_SLOT3")
		)
		(pad "2" smd rect
			(at 0 0.9652 180)
			(size 1.397 1.143)
			(layers "F.Cu" "F.Mask" "F.Paste")
			(net "GND")
		)
	)
	(footprint ""
		(layer "F.Cu")
		(at 124.4092 -21.1074)
		(property "Reference" "R66"
			(at 0 0 0)
			(layer "F.SilkS")
			(hide yes)
			(effects
				(font
					(size 1.27 1.27)
				)
			)
		)
		(property "Value" "4K7R2F-GP"
			(at 0.064008 -3.993896 0)
			(unlocked yes)
			(layer "F.Fab")
			(hide yes)
			(effects
				(font
					(size 1.016 1.016)
					(thickness 0.1524)
				)
			)
		)
		(property "Device Type" "R402H16"
			(at 0.064008 -5.517896 0)
			(unlocked yes)
			(layer "F.Fab")
			(hide yes)
			(effects
				(font
					(size 1.016 1.016)
					(thickness 0.1524)
				)
			)
		)
		(duplicate_pad_numbers_are_jumpers no)
		(fp_line
			(start -0.508 -0.9398)
			(end -0.508 0.9398)
			(stroke
				(width 0.1524)
				(type default)
			)
			(layer "F.SilkS")
		)
		(fp_line
			(start 0.508 -0.9398)
			(end -0.508 -0.9398)
			(stroke
				(width 0.1524)
				(type default)
			)
			(layer "F.SilkS")
		)
		(fp_rect
			(start -0.508 0.9398)
			(end 0.508 -0.9398)
			(stroke
				(width 0)
				(type default)
			)
			(fill no)
			(layer "F.CrtYd")
		)
		(fp_rect
			(start -0.508 0.9398)
			(end 0.508 -0.9398)
			(stroke
				(width 0)
				(type default)
			)
			(fill no)
			(layer "F.Fab")
		)
		(pad "1" smd custom
			(at 0 -0.4445)
			(size 0.1397 0.1397)
			(layers "F.Cu" "F.Mask" "F.Paste")
			(net "P3V3_STBY")
			(options
				(clearance outline)
				(anchor circle)
			)
			(primitives
				(gr_poly
					(pts
						(arc
							(start -0.1778 -0.2794)
							(mid -0.249642 -0.249642)
							(end -0.2794 -0.1778)
						)
						(arc
							(start -0.2794 0.1778)
							(mid -0.249642 0.249642)
							(end -0.1778 0.2794)
						)
						(arc
							(start 0.1778 0.2794)
							(mid 0.249642 0.249642)
							(end 0.2794 0.1778)
						)
						(arc
							(start 0.2794 -0.1778)
							(mid 0.249642 -0.249642)
							(end 0.1778 -0.2794)
						)
					)
					(width 0)
					(fill yes)
				)
			)
		)
		(pad "2" smd custom
			(at 0 0.4445)
			(size 0.1397 0.1397)
			(layers "F.Cu" "F.Mask" "F.Paste")
			(net "GPIO_B_EXP_INT_N")
			(options
				(clearance outline)
				(anchor circle)
			)
			(primitives
				(gr_poly
					(pts
						(arc
							(start -0.1778 -0.2794)
							(mid -0.249642 -0.249642)
							(end -0.2794 -0.1778)
						)
						(arc
							(start -0.2794 0.1778)
							(mid -0.249642 0.249642)
							(end -0.1778 0.2794)
						)
						(arc
							(start 0.1778 0.2794)
							(mid 0.249642 0.249642)
							(end 0.2794 0.1778)
						)
						(arc
							(start 0.2794 -0.1778)
							(mid 0.249642 -0.249642)
							(end 0.1778 -0.2794)
						)
					)
					(width 0)
					(fill yes)
				)
			)
		)
	)
)
